(kicad_pcb
	(version 20260206)
	(generator "pcbnew")
	(generator_version "10.0")
	(general
		(thickness 1.6)
		(legacy_teardrops no)
	)
	(paper "A4")
	(title_block
		(title "03242023_DA0F0TMBIJ0_F0T_Motherboard_J_brd_V01_OCP.brd")
		(comment 1 "Grand Teton / footprint 652 of 6105 (J8), pads 1-112 of 291")
	)
	(layers
		(0 "F.Cu" signal "TOP")
		(4 "In1.Cu" signal "GND")
		(6 "In2.Cu" signal "IN1")
		(8 "In3.Cu" signal "GND1")
		(10 "In4.Cu" signal "IN2")
		(12 "In5.Cu" signal "GND2")
		(14 "In6.Cu" signal "IN3")
		(16 "In7.Cu" signal "GND3")
		(18 "In8.Cu" signal "VCC")
		(20 "In9.Cu" signal "VCC1")
		(22 "In10.Cu" signal "GND4")
		(24 "In11.Cu" signal "IN4")
		(26 "In12.Cu" signal "GND5")
		(28 "In13.Cu" signal "IN5")
		(30 "In14.Cu" signal "GND6")
		(32 "In15.Cu" signal "IN6")
		(34 "In16.Cu" signal "GND7")
		(2 "B.Cu" signal "BOTTOM")
		(9 "F.Adhes" user "F.Adhesive")
		(11 "B.Adhes" user "B.Adhesive")
		(13 "F.Paste" user "Package Geometry/Pastemask Top")
		(15 "B.Paste" user "Package Geometry/Pastemask Bottom")
		(5 "F.SilkS" user "Ref Des/Silkscreen Top")
		(7 "B.SilkS" user "Ref Des/Silkscreen Bottom")
		(1 "F.Mask" user "Board Geometry/Soldermask Top")
		(3 "B.Mask" user "Board Geometry/Soldermask Bottom")
		(17 "Dwgs.User" user "User.Drawings")
		(19 "Cmts.User" user "User.Comments")
		(21 "Eco1.User" user "User.Eco1")
		(23 "Eco2.User" user "User.Eco2")
		(25 "Edge.Cuts" user "Board Geometry/Outline")
		(27 "Margin" user)
		(31 "F.CrtYd" user "Package Geometry/Place Bound Top")
		(29 "B.CrtYd" user "Package Geometry/Place Bound Bottom")
		(35 "F.Fab" user "Ref Des/Assembly Top")
		(33 "B.Fab" user "Ref Des/Assembly Bottom")
	)
	(footprint ""
		(layer "F.Cu")
		(at 265.674348 -258.091686)
		(property "Reference" "J8"
			(at -3.683 -81.702148 0)
			(unlocked yes)
			(layer "F.SilkS")
			(effects
				(font
					(size 0.7874 0.5842)
					(thickness 0.1524)
				)
				(justify left)
			)
		)
		(property "Value" ""
			(at 0 0 0)
			(layer "F.Fab")
			(effects
				(font
					(size 1.27 1.27)
				)
			)
		)
		(duplicate_pad_numbers_are_jumpers no)
		(pad "1" smd rect
			(at -2.050034 -63.324994 270)
			(size 0.519938 1.4986)
			(layers "F.Cu" "F.Mask" "F.Paste")
			(net "P12V_S3_AUX_CPU0_NVDIMM")
		)
		(pad "2" smd rect
			(at -2.050034 -62.47511 270)
			(size 0.519938 1.4986)
			(layers "F.Cu" "F.Mask" "F.Paste")
			(net "TP_CHD_CPU0_DIMM2_FRU_0")
		)
		(pad "3" smd rect
			(at -2.050034 -61.624972 270)
			(size 0.519938 1.4986)
			(layers "F.Cu" "F.Mask" "F.Paste")
			(net "P3V3_AUX")
		)
		(pad "4" smd rect
			(at -2.050034 -60.775088 270)
			(size 0.519938 1.4986)
			(layers "F.Cu" "F.Mask" "F.Paste")
			(net "I3C_SPD_DDRABCD_CPU0_LVC1_SCL_7")
		)
		(pad "5" smd rect
			(at -2.050034 -59.92495 270)
			(size 0.519938 1.4986)
			(layers "F.Cu" "F.Mask" "F.Paste")
			(net "I3C_SPD_DDRABCD_CPU0_LVC1_SDA")
		)
		(pad "6" smd rect
			(at -2.050034 -59.075066 270)
			(size 0.519938 1.4986)
			(layers "F.Cu" "F.Mask" "F.Paste")
			(net "GND")
		)
		(pad "7" smd rect
			(at -2.050034 -58.224928 270)
			(size 0.519938 1.4986)
			(layers "F.Cu" "F.Mask" "F.Paste")
			(net "M_D_CPU0_SA_DQ<0>")
		)
		(pad "8" smd rect
			(at -2.050034 -57.375044 270)
			(size 0.519938 1.4986)
			(layers "F.Cu" "F.Mask" "F.Paste")
			(net "GND")
		)
		(pad "9" smd rect
			(at -2.050034 -56.524906 270)
			(size 0.519938 1.4986)
			(layers "F.Cu" "F.Mask" "F.Paste")
			(net "M_D_CPU0_SA_DQ<1>")
		)
		(pad "10" smd rect
			(at -2.050034 -55.675022 270)
			(size 0.519938 1.4986)
			(layers "F.Cu" "F.Mask" "F.Paste")
			(net "GND")
		)
		(pad "11" smd rect
			(at -2.050034 -54.824884 270)
			(size 0.519938 1.4986)
			(layers "F.Cu" "F.Mask" "F.Paste")
			(net "M_D_CPU0_SA_DQS_DP<0>")
		)
		(pad "12" smd rect
			(at -2.050034 -53.975 270)
			(size 0.519938 1.4986)
			(layers "F.Cu" "F.Mask" "F.Paste")
			(net "M_D_CPU0_SA_DQS_DN<0>")
		)
		(pad "13" smd rect
			(at -2.050034 -53.125116 270)
			(size 0.519938 1.4986)
			(layers "F.Cu" "F.Mask" "F.Paste")
			(net "GND")
		)
		(pad "14" smd rect
			(at -2.050034 -52.274978 270)
			(size 0.519938 1.4986)
			(layers "F.Cu" "F.Mask" "F.Paste")
			(net "M_D_CPU0_SA_DQ<4>")
		)
		(pad "15" smd rect
			(at -2.050034 -51.425094 270)
			(size 0.519938 1.4986)
			(layers "F.Cu" "F.Mask" "F.Paste")
			(net "GND")
		)
		(pad "16" smd rect
			(at -2.050034 -50.574956 270)
			(size 0.519938 1.4986)
			(layers "F.Cu" "F.Mask" "F.Paste")
			(net "M_D_CPU0_SA_DQ<5>")
		)
		(pad "17" smd rect
			(at -2.050034 -49.725072 270)
			(size 0.519938 1.4986)
			(layers "F.Cu" "F.Mask" "F.Paste")
			(net "GND")
		)
		(pad "18" smd rect
			(at -2.050034 -48.874934 270)
			(size 0.519938 1.4986)
			(layers "F.Cu" "F.Mask" "F.Paste")
			(net "M_D_CPU0_SA_DQ<8>")
		)
		(pad "19" smd rect
			(at -2.050034 -48.02505 270)
			(size 0.519938 1.4986)
			(layers "F.Cu" "F.Mask" "F.Paste")
			(net "GND")
		)
		(pad "20" smd rect
			(at -2.050034 -47.174912 270)
			(size 0.519938 1.4986)
			(layers "F.Cu" "F.Mask" "F.Paste")
			(net "M_D_CPU0_SA_DQ<9>")
		)
		(pad "21" smd rect
			(at -2.050034 -46.325028 270)
			(size 0.519938 1.4986)
			(layers "F.Cu" "F.Mask" "F.Paste")
			(net "GND")
		)
		(pad "22" smd rect
			(at -2.050034 -45.47489 270)
			(size 0.519938 1.4986)
			(layers "F.Cu" "F.Mask" "F.Paste")
			(net "M_D_CPU0_SA_DQS_DP<1>")
		)
		(pad "23" smd rect
			(at -2.050034 -44.625006 270)
			(size 0.519938 1.4986)
			(layers "F.Cu" "F.Mask" "F.Paste")
			(net "M_D_CPU0_SA_DQS_DN<1>")
		)
		(pad "24" smd rect
			(at -2.050034 -43.775122 270)
			(size 0.519938 1.4986)
			(layers "F.Cu" "F.Mask" "F.Paste")
			(net "GND")
		)
		(pad "25" smd rect
			(at -2.050034 -42.924984 270)
			(size 0.519938 1.4986)
			(layers "F.Cu" "F.Mask" "F.Paste")
			(net "M_D_CPU0_SA_DQ<12>")
		)
		(pad "26" smd rect
			(at -2.050034 -42.0751 270)
			(size 0.519938 1.4986)
			(layers "F.Cu" "F.Mask" "F.Paste")
			(net "GND")
		)
		(pad "27" smd rect
			(at -2.050034 -41.224962 270)
			(size 0.519938 1.4986)
			(layers "F.Cu" "F.Mask" "F.Paste")
			(net "M_D_CPU0_SA_DQ<13>")
		)
		(pad "28" smd rect
			(at -2.050034 -40.375078 270)
			(size 0.519938 1.4986)
			(layers "F.Cu" "F.Mask" "F.Paste")
			(net "GND")
		)
		(pad "29" smd rect
			(at -2.050034 -39.52494 270)
			(size 0.519938 1.4986)
			(layers "F.Cu" "F.Mask" "F.Paste")
			(net "M_D_CPU0_SA_DQ<16>")
		)
		(pad "30" smd rect
			(at -2.050034 -38.675056 270)
			(size 0.519938 1.4986)
			(layers "F.Cu" "F.Mask" "F.Paste")
			(net "GND")
		)
		(pad "31" smd rect
			(at -2.050034 -37.824918 270)
			(size 0.519938 1.4986)
			(layers "F.Cu" "F.Mask" "F.Paste")
			(net "M_D_CPU0_SA_DQ<17>")
		)
		(pad "32" smd rect
			(at -2.050034 -36.975034 270)
			(size 0.519938 1.4986)
			(layers "F.Cu" "F.Mask" "F.Paste")
			(net "GND")
		)
		(pad "33" smd rect
			(at -2.050034 -36.124896 270)
			(size 0.519938 1.4986)
			(layers "F.Cu" "F.Mask" "F.Paste")
			(net "M_D_CPU0_SA_DQS_DP<2>")
		)
		(pad "34" smd rect
			(at -2.050034 -35.275012 270)
			(size 0.519938 1.4986)
			(layers "F.Cu" "F.Mask" "F.Paste")
			(net "M_D_CPU0_SA_DQS_DN<2>")
		)
		(pad "35" smd rect
			(at -2.050034 -34.425128 270)
			(size 0.519938 1.4986)
			(layers "F.Cu" "F.Mask" "F.Paste")
			(net "GND")
		)
		(pad "36" smd rect
			(at -2.050034 -33.57499 270)
			(size 0.519938 1.4986)
			(layers "F.Cu" "F.Mask" "F.Paste")
			(net "M_D_CPU0_SA_DQ<20>")
		)
		(pad "37" smd rect
			(at -2.050034 -32.725106 270)
			(size 0.519938 1.4986)
			(layers "F.Cu" "F.Mask" "F.Paste")
			(net "GND")
		)
		(pad "38" smd rect
			(at -2.050034 -31.874968 270)
			(size 0.519938 1.4986)
			(layers "F.Cu" "F.Mask" "F.Paste")
			(net "M_D_CPU0_SA_DQ<21>")
		)
		(pad "39" smd rect
			(at -2.050034 -31.025084 270)
			(size 0.519938 1.4986)
			(layers "F.Cu" "F.Mask" "F.Paste")
			(net "GND")
		)
		(pad "40" smd rect
			(at -2.050034 -30.174946 270)
			(size 0.519938 1.4986)
			(layers "F.Cu" "F.Mask" "F.Paste")
			(net "M_D_CPU0_SA_DQ<24>")
		)
		(pad "41" smd rect
			(at -2.050034 -29.325062 270)
			(size 0.519938 1.4986)
			(layers "F.Cu" "F.Mask" "F.Paste")
			(net "GND")
		)
		(pad "42" smd rect
			(at -2.050034 -28.474924 270)
			(size 0.519938 1.4986)
			(layers "F.Cu" "F.Mask" "F.Paste")
			(net "M_D_CPU0_SA_DQ<25>")
		)
		(pad "43" smd rect
			(at -2.050034 -27.62504 270)
			(size 0.519938 1.4986)
			(layers "F.Cu" "F.Mask" "F.Paste")
			(net "GND")
		)
		(pad "44" smd rect
			(at -2.050034 -26.774902 270)
			(size 0.519938 1.4986)
			(layers "F.Cu" "F.Mask" "F.Paste")
			(net "M_D_CPU0_SA_DQS_DP<3>")
		)
		(pad "45" smd rect
			(at -2.050034 -25.925018 270)
			(size 0.519938 1.4986)
			(layers "F.Cu" "F.Mask" "F.Paste")
			(net "M_D_CPU0_SA_DQS_DN<3>")
		)
		(pad "46" smd rect
			(at -2.050034 -25.07488 270)
			(size 0.519938 1.4986)
			(layers "F.Cu" "F.Mask" "F.Paste")
			(net "GND")
		)
		(pad "47" smd rect
			(at -2.050034 -24.224996 270)
			(size 0.519938 1.4986)
			(layers "F.Cu" "F.Mask" "F.Paste")
			(net "M_D_CPU0_SA_DQ<28>")
		)
		(pad "48" smd rect
			(at -2.050034 -23.375112 270)
			(size 0.519938 1.4986)
			(layers "F.Cu" "F.Mask" "F.Paste")
			(net "GND")
		)
		(pad "49" smd rect
			(at -2.050034 -22.524974 270)
			(size 0.519938 1.4986)
			(layers "F.Cu" "F.Mask" "F.Paste")
			(net "M_D_CPU0_SA_DQ<29>")
		)
		(pad "50" smd rect
			(at -2.050034 -21.67509 270)
			(size 0.519938 1.4986)
			(layers "F.Cu" "F.Mask" "F.Paste")
			(net "GND")
		)
		(pad "51" smd rect
			(at -2.050034 -20.824952 270)
			(size 0.519938 1.4986)
			(layers "F.Cu" "F.Mask" "F.Paste")
			(net "M_D_CPU0_SA_CB<0>")
		)
		(pad "52" smd rect
			(at -2.050034 -19.975068 270)
			(size 0.519938 1.4986)
			(layers "F.Cu" "F.Mask" "F.Paste")
			(net "GND")
		)
		(pad "53" smd rect
			(at -2.050034 -19.12493 270)
			(size 0.519938 1.4986)
			(layers "F.Cu" "F.Mask" "F.Paste")
			(net "M_D_CPU0_SA_CB<1>")
		)
		(pad "54" smd rect
			(at -2.050034 -18.275046 270)
			(size 0.519938 1.4986)
			(layers "F.Cu" "F.Mask" "F.Paste")
			(net "GND")
		)
		(pad "55" smd rect
			(at -2.050034 -17.424908 270)
			(size 0.519938 1.4986)
			(layers "F.Cu" "F.Mask" "F.Paste")
			(net "M_D_CPU0_SA_DQS_DP<4>")
		)
		(pad "56" smd rect
			(at -2.050034 -16.575024 270)
			(size 0.519938 1.4986)
			(layers "F.Cu" "F.Mask" "F.Paste")
			(net "M_D_CPU0_SA_DQS_DN<4>")
		)
		(pad "57" smd rect
			(at -2.050034 -15.724886 270)
			(size 0.519938 1.4986)
			(layers "F.Cu" "F.Mask" "F.Paste")
			(net "GND")
		)
		(pad "58" smd rect
			(at -2.050034 -14.875002 270)
			(size 0.519938 1.4986)
			(layers "F.Cu" "F.Mask" "F.Paste")
			(net "M_D_CPU0_SA_CB<4>")
		)
		(pad "59" smd rect
			(at -2.050034 -14.025118 270)
			(size 0.519938 1.4986)
			(layers "F.Cu" "F.Mask" "F.Paste")
			(net "GND")
		)
		(pad "60" smd rect
			(at -2.050034 -13.17498 270)
			(size 0.519938 1.4986)
			(layers "F.Cu" "F.Mask" "F.Paste")
			(net "M_D_CPU0_SA_CB<5>")
		)
		(pad "61" smd rect
			(at -2.050034 -12.325096 270)
			(size 0.519938 1.4986)
			(layers "F.Cu" "F.Mask" "F.Paste")
			(net "GND")
		)
		(pad "62" smd rect
			(at -2.050034 -11.474958 270)
			(size 0.519938 1.4986)
			(layers "F.Cu" "F.Mask" "F.Paste")
			(net "M_D_CPU0_ALERT_N")
		)
		(pad "63" smd rect
			(at -2.050034 -10.625074 270)
			(size 0.519938 1.4986)
			(layers "F.Cu" "F.Mask" "F.Paste")
			(net "GND")
		)
		(pad "64" smd rect
			(at -2.050034 -9.774936 270)
			(size 0.519938 1.4986)
			(layers "F.Cu" "F.Mask" "F.Paste")
			(net "M_D_CPU0_SA_CS_N<2>")
		)
		(pad "65" smd rect
			(at -2.050034 -8.925052 270)
			(size 0.519938 1.4986)
			(layers "F.Cu" "F.Mask" "F.Paste")
			(net "GND")
		)
		(pad "66" smd rect
			(at -2.050034 -8.074914 270)
			(size 0.519938 1.4986)
			(layers "F.Cu" "F.Mask" "F.Paste")
			(net "M_D_CPU0_SA_CA<0>")
		)
		(pad "67" smd rect
			(at -2.050034 -7.22503 270)
			(size 0.519938 1.4986)
			(layers "F.Cu" "F.Mask" "F.Paste")
			(net "GND")
		)
		(pad "68" smd rect
			(at -2.050034 -6.374892 270)
			(size 0.519938 1.4986)
			(layers "F.Cu" "F.Mask" "F.Paste")
			(net "M_D_CPU0_SA_CA<2>")
		)
		(pad "69" smd rect
			(at -2.050034 -5.525008 270)
			(size 0.519938 1.4986)
			(layers "F.Cu" "F.Mask" "F.Paste")
			(net "GND")
		)
		(pad "70" smd rect
			(at -2.050034 -4.675124 270)
			(size 0.519938 1.4986)
			(layers "F.Cu" "F.Mask" "F.Paste")
			(net "M_D_CPU0_SA_CA<4>")
		)
		(pad "71" smd rect
			(at -2.050034 -3.824986 270)
			(size 0.519938 1.4986)
			(layers "F.Cu" "F.Mask" "F.Paste")
			(net "GND")
		)
		(pad "72" smd rect
			(at -2.050034 -2.975102 270)
			(size 0.519938 1.4986)
			(layers "F.Cu" "F.Mask" "F.Paste")
			(net "M_D_CPU0_SA_CA<6>")
		)
		(pad "73" smd rect
			(at -2.050034 -2.124964 270)
			(size 0.519938 1.4986)
			(layers "F.Cu" "F.Mask" "F.Paste")
			(net "GND")
		)
		(pad "74" smd rect
			(at -2.050034 -1.27508 270)
			(size 0.519938 1.4986)
			(layers "F.Cu" "F.Mask" "F.Paste")
			(net "M_D_CPU0_SA_PAR")
		)
		(pad "75" smd rect
			(at -2.050034 -0.424942 270)
			(size 0.519938 1.4986)
			(layers "F.Cu" "F.Mask" "F.Paste")
			(net "GND")
		)
		(pad "76" smd rect
			(at -2.050034 5.525008 270)
			(size 0.519938 1.4986)
			(layers "F.Cu" "F.Mask" "F.Paste")
			(net "M_D_CPU0_SB_CA<0>")
		)
		(pad "77" smd rect
			(at -2.050034 6.374892 270)
			(size 0.519938 1.4986)
			(layers "F.Cu" "F.Mask" "F.Paste")
			(net "GND")
		)
		(pad "78" smd rect
			(at -2.050034 7.22503 270)
			(size 0.519938 1.4986)
			(layers "F.Cu" "F.Mask" "F.Paste")
			(net "M_D_CPU0_SB_CA<2>")
		)
		(pad "79" smd rect
			(at -2.050034 8.074914 270)
			(size 0.519938 1.4986)
			(layers "F.Cu" "F.Mask" "F.Paste")
			(net "GND")
		)
		(pad "80" smd rect
			(at -2.050034 8.925052 270)
			(size 0.519938 1.4986)
			(layers "F.Cu" "F.Mask" "F.Paste")
			(net "M_D_CPU0_SB_CA<4>")
		)
		(pad "81" smd rect
			(at -2.050034 9.774936 270)
			(size 0.519938 1.4986)
			(layers "F.Cu" "F.Mask" "F.Paste")
			(net "GND")
		)
		(pad "82" smd rect
			(at -2.050034 10.625074 270)
			(size 0.519938 1.4986)
			(layers "F.Cu" "F.Mask" "F.Paste")
			(net "M_D_CPU0_SB_CA<6>")
		)
		(pad "83" smd rect
			(at -2.050034 11.474958 270)
			(size 0.519938 1.4986)
			(layers "F.Cu" "F.Mask" "F.Paste")
			(net "GND")
		)
		(pad "84" smd rect
			(at -2.050034 12.325096 270)
			(size 0.519938 1.4986)
			(layers "F.Cu" "F.Mask" "F.Paste")
			(net "M_D_CPU0_SB_CS_N<2>")
		)
		(pad "85" smd rect
			(at -2.050034 13.17498 270)
			(size 0.519938 1.4986)
			(layers "F.Cu" "F.Mask" "F.Paste")
			(net "GND")
		)
		(pad "86" smd rect
			(at -2.050034 14.025118 270)
			(size 0.519938 1.4986)
			(layers "F.Cu" "F.Mask" "F.Paste")
			(net "M_D_CPU0_SA_RSP<1>")
		)
		(pad "87" smd rect
			(at -2.050034 14.875002 270)
			(size 0.519938 1.4986)
			(layers "F.Cu" "F.Mask" "F.Paste")
			(net "M_D_CPU0_SB_RSP<1>")
		)
		(pad "88" smd rect
			(at -2.050034 15.724886 270)
			(size 0.519938 1.4986)
			(layers "F.Cu" "F.Mask" "F.Paste")
			(net "GND")
		)
		(pad "89" smd rect
			(at -2.050034 16.575024 270)
			(size 0.519938 1.4986)
			(layers "F.Cu" "F.Mask" "F.Paste")
			(net "M_D_CPU0_SB_CB<4>")
		)
		(pad "90" smd rect
			(at -2.050034 17.424908 270)
			(size 0.519938 1.4986)
			(layers "F.Cu" "F.Mask" "F.Paste")
			(net "GND")
		)
		(pad "91" smd rect
			(at -2.050034 18.275046 270)
			(size 0.519938 1.4986)
			(layers "F.Cu" "F.Mask" "F.Paste")
			(net "M_D_CPU0_SB_CB<5>")
		)
		(pad "92" smd rect
			(at -2.050034 19.12493 270)
			(size 0.519938 1.4986)
			(layers "F.Cu" "F.Mask" "F.Paste")
			(net "GND")
		)
		(pad "93" smd rect
			(at -2.050034 19.975068 270)
			(size 0.519938 1.4986)
			(layers "F.Cu" "F.Mask" "F.Paste")
			(net "M_D_CPU0_SB_DQS_DP<9>")
		)
		(pad "94" smd rect
			(at -2.050034 20.824952 270)
			(size 0.519938 1.4986)
			(layers "F.Cu" "F.Mask" "F.Paste")
			(net "M_D_CPU0_SB_DQS_DN<9>")
		)
		(pad "95" smd rect
			(at -2.050034 21.67509 270)
			(size 0.519938 1.4986)
			(layers "F.Cu" "F.Mask" "F.Paste")
			(net "GND")
		)
		(pad "96" smd rect
			(at -2.050034 22.524974 270)
			(size 0.519938 1.4986)
			(layers "F.Cu" "F.Mask" "F.Paste")
			(net "M_D_CPU0_SB_CB<0>")
		)
		(pad "97" smd rect
			(at -2.050034 23.375112 270)
			(size 0.519938 1.4986)
			(layers "F.Cu" "F.Mask" "F.Paste")
			(net "GND")
		)
		(pad "98" smd rect
			(at -2.050034 24.224996 270)
			(size 0.519938 1.4986)
			(layers "F.Cu" "F.Mask" "F.Paste")
			(net "M_D_CPU0_SB_CB<1>")
		)
		(pad "99" smd rect
			(at -2.050034 25.07488 270)
			(size 0.519938 1.4986)
			(layers "F.Cu" "F.Mask" "F.Paste")
			(net "GND")
		)
		(pad "100" smd rect
			(at -2.050034 25.925018 270)
			(size 0.519938 1.4986)
			(layers "F.Cu" "F.Mask" "F.Paste")
			(net "M_D_CPU0_SB_DQ<0>")
		)
		(pad "101" smd rect
			(at -2.050034 26.774902 270)
			(size 0.519938 1.4986)
			(layers "F.Cu" "F.Mask" "F.Paste")
			(net "GND")
		)
		(pad "102" smd rect
			(at -2.050034 27.62504 270)
			(size 0.519938 1.4986)
			(layers "F.Cu" "F.Mask" "F.Paste")
			(net "M_D_CPU0_SB_DQ<1>")
		)
		(pad "103" smd rect
			(at -2.050034 28.474924 270)
			(size 0.519938 1.4986)
			(layers "F.Cu" "F.Mask" "F.Paste")
			(net "GND")
		)
		(pad "104" smd rect
			(at -2.050034 29.325062 270)
			(size 0.519938 1.4986)
			(layers "F.Cu" "F.Mask" "F.Paste")
			(net "M_D_CPU0_SB_DQS_DP<0>")
		)
		(pad "105" smd rect
			(at -2.050034 30.174946 270)
			(size 0.519938 1.4986)
			(layers "F.Cu" "F.Mask" "F.Paste")
			(net "M_D_CPU0_SB_DQS_DN<0>")
		)
		(pad "106" smd rect
			(at -2.050034 31.025084 270)
			(size 0.519938 1.4986)
			(layers "F.Cu" "F.Mask" "F.Paste")
			(net "GND")
		)
		(pad "107" smd rect
			(at -2.050034 31.874968 270)
			(size 0.519938 1.4986)
			(layers "F.Cu" "F.Mask" "F.Paste")
			(net "M_D_CPU0_SB_DQ<4>")
		)
		(pad "108" smd rect
			(at -2.050034 32.725106 270)
			(size 0.519938 1.4986)
			(layers "F.Cu" "F.Mask" "F.Paste")
			(net "GND")
		)
		(pad "109" smd rect
			(at -2.050034 33.57499 270)
			(size 0.519938 1.4986)
			(layers "F.Cu" "F.Mask" "F.Paste")
			(net "M_D_CPU0_SB_DQ<5>")
		)
		(pad "110" smd rect
			(at -2.050034 34.425128 270)
			(size 0.519938 1.4986)
			(layers "F.Cu" "F.Mask" "F.Paste")
			(net "GND")
		)
		(pad "111" smd rect
			(at -2.050034 35.275012 270)
			(size 0.519938 1.4986)
			(layers "F.Cu" "F.Mask" "F.Paste")
			(net "M_D_CPU0_SB_DQ<8>")
		)
		(pad "112" smd rect
			(at -2.050034 36.124896 270)
			(size 0.519938 1.4986)
			(layers "F.Cu" "F.Mask" "F.Paste")
			(net "GND")
		)
	)
)
